# T6G (Grand Teton) — schematic netlist excerpt (pin names and nets, part order shuffled) for the footprints in the layout excerpt that follows; sources: Cadence DE-HDL packaged netlist, KiCad conversion of 04192023_DAF0TMB3IC0_F0TG_MB_C_brd_V02_OCP.brd

R3858  Q_RES  33.2 1% CHIP  pkg 0402LF  page 150 : A = SMB_OCP_V3_2_3V3AUX_SDA ; B = SMB_OCP_V3_2_3V3AUX_SDA_R0
R2416  Q_RES  33.2 1% CHIP  pkg 0402LF  page 150 : A = SMB_1_BMC_GPU_SDA ; B = SMB_PCIE3_3V3AUX_SDA_R
PC7002  Q_CAP  22UF 16V 20% X6S  pkg C0805  page 208 : A = SW_P12V_AUX_PVDD11_S3_P0_FLT ; B = GND

(kicad_pcb
	(version 20260206)
	(generator "pcbnew")
	(generator_version "10.0")
	(general
		(thickness 1.6)
		(legacy_teardrops no)
	)
	(paper "A4")
	(title_block
		(title "04192023_DAF0TMB3IC0_F0TG_MB_C_brd_V02_OCP.brd")
		(comment 1 "Grand Teton / footprints 6108-6110 of 8354")
	)
	(layers
		(0 "F.Cu" signal "TOP")
		(4 "In1.Cu" signal "GND")
		(6 "In2.Cu" signal "IN1")
		(8 "In3.Cu" signal "GND1")
		(10 "In4.Cu" signal "IN2")
		(12 "In5.Cu" signal "GND2")
		(14 "In6.Cu" signal "IN3")
		(16 "In7.Cu" signal "GND3")
		(18 "In8.Cu" signal "VCC")
		(20 "In9.Cu" signal "VCC1")
		(22 "In10.Cu" signal "GND4")
		(24 "In11.Cu" signal "IN4")
		(26 "In12.Cu" signal "GND5")
		(28 "In13.Cu" signal "IN5")
		(30 "In14.Cu" signal "GND6")
		(32 "In15.Cu" signal "IN6")
		(34 "In16.Cu" signal "GND7")
		(2 "B.Cu" signal "BOTTOM")
		(9 "F.Adhes" user "F.Adhesive")
		(11 "B.Adhes" user "B.Adhesive")
		(13 "F.Paste" user "Package Geometry/Pastemask Top")
		(15 "B.Paste" user "Package Geometry/Pastemask Bottom")
		(5 "F.SilkS" user "Ref Des/Silkscreen Top")
		(7 "B.SilkS" user "Ref Des/Silkscreen Bottom")
		(1 "F.Mask" user "Board Geometry/Soldermask Top")
		(3 "B.Mask" user "Board Geometry/Soldermask Bottom")
		(17 "Dwgs.User" user "User.Drawings")
		(19 "Cmts.User" user "User.Comments")
		(21 "Eco1.User" user "User.Eco1")
		(23 "Eco2.User" user "User.Eco2")
		(25 "Edge.Cuts" user "Board Geometry/Outline")
		(27 "Margin" user)
		(31 "F.CrtYd" user "Package Geometry/Place Bound Top")
		(29 "B.CrtYd" user "Package Geometry/Place Bound Bottom")
		(35 "F.Fab" user "Ref Des/Assembly Top")
		(33 "B.Fab" user "Ref Des/Assembly Bottom")
	)
	(footprint ""
		(layer "B.Cu")
		(at 170.424856 -8.062468 -90)
		(property "Reference" "R3858"
			(at 0 0 90)
			(layer "B.SilkS")
			(hide yes)
			(effects
				(font
					(size 1.27 1.27)
				)
				(justify mirror)
			)
		)
		(property "Value" ""
			(at 0 0 90)
			(layer "B.Fab")
			(effects
				(font
					(size 1.27 1.27)
				)
				(justify mirror)
			)
		)
		(duplicate_pad_numbers_are_jumpers no)
		(fp_line
			(start -0.7874 0.4064)
			(end 0.7874 0.4064)
			(stroke
				(width 0.1524)
				(type default)
			)
			(layer "B.SilkS")
		)
		(fp_line
			(start 0.7874 0.4064)
			(end 0.7874 -0.4064)
			(stroke
				(width 0.1524)
				(type default)
			)
			(layer "B.SilkS")
		)
		(fp_line
			(start -0.7874 -0.4064)
			(end -0.7874 0.4064)
			(stroke
				(width 0.1524)
				(type default)
			)
			(layer "B.SilkS")
		)
		(fp_line
			(start 0.7874 -0.4064)
			(end -0.7874 -0.4064)
			(stroke
				(width 0.1524)
				(type default)
			)
			(layer "B.SilkS")
		)
		(fp_line
			(start -0.67945 0.3048)
			(end -0.120396 0.3048)
			(stroke
				(width 0.1)
				(type default)
			)
			(layer "B.Fab")
		)
		(fp_line
			(start -0.120396 0.3048)
			(end -0.120396 0.2794)
			(stroke
				(width 0.1)
				(type default)
			)
			(layer "B.Fab")
		)
		(fp_line
			(start 0.12065 0.3048)
			(end 0.67945 0.3048)
			(stroke
				(width 0.1)
				(type default)
			)
			(layer "B.Fab")
		)
		(fp_line
			(start 0.67945 0.3048)
			(end 0.67945 -0.305054)
			(stroke
				(width 0.1)
				(type default)
			)
			(layer "B.Fab")
		)
		(fp_line
			(start -0.120396 0.2794)
			(end 0.12065 0.2794)
			(stroke
				(width 0.1)
				(type default)
			)
			(layer "B.Fab")
		)
		(fp_line
			(start 0.12065 0.2794)
			(end 0.12065 0.3048)
			(stroke
				(width 0.1)
				(type default)
			)
			(layer "B.Fab")
		)
		(fp_line
			(start -0.12065 -0.2794)
			(end -0.12065 -0.3048)
			(stroke
				(width 0.1)
				(type default)
			)
			(layer "B.Fab")
		)
		(fp_line
			(start 0.12065 -0.2794)
			(end -0.12065 -0.2794)
			(stroke
				(width 0.1)
				(type default)
			)
			(layer "B.Fab")
		)
		(fp_line
			(start -0.67945 -0.3048)
			(end -0.67945 0.3048)
			(stroke
				(width 0.1)
				(type default)
			)
			(layer "B.Fab")
		)
		(fp_line
			(start -0.12065 -0.3048)
			(end -0.67945 -0.3048)
			(stroke
				(width 0.1)
				(type default)
			)
			(layer "B.Fab")
		)
		(fp_line
			(start 0.12065 -0.305054)
			(end 0.12065 -0.2794)
			(stroke
				(width 0.1)
				(type default)
			)
			(layer "B.Fab")
		)
		(fp_line
			(start 0.67945 -0.305054)
			(end 0.12065 -0.305054)
			(stroke
				(width 0.1)
				(type default)
			)
			(layer "B.Fab")
		)
		(pad "1" smd circle
			(at 0.40005 0 90)
			(size 0 0)
			(layers "B.Cu" "B.Mask" "B.Paste")
			(net "SMB_OCP_V3_2_3V3AUX_SDA")
		)
		(pad "2" smd circle
			(at -0.40005 0 90)
			(size 0 0)
			(layers "B.Cu" "B.Mask" "B.Paste")
			(net "SMB_OCP_V3_2_3V3AUX_SDA_R0")
		)
	)
	(footprint ""
		(layer "B.Cu")
		(at 152.9969 -13.762228 90)
		(property "Reference" "R2416"
			(at 0 0 90)
			(layer "B.SilkS")
			(hide yes)
			(effects
				(font
					(size 1.27 1.27)
				)
				(justify mirror)
			)
		)
		(property "Value" ""
			(at 0 0 90)
			(layer "B.Fab")
			(effects
				(font
					(size 1.27 1.27)
				)
				(justify mirror)
			)
		)
		(duplicate_pad_numbers_are_jumpers no)
		(fp_line
			(start 0.7874 -0.4064)
			(end -0.7874 -0.4064)
			(stroke
				(width 0.1524)
				(type default)
			)
			(layer "B.SilkS")
		)
		(fp_line
			(start -0.7874 -0.4064)
			(end -0.7874 0.4064)
			(stroke
				(width 0.1524)
				(type default)
			)
			(layer "B.SilkS")
		)
		(fp_line
			(start 0.7874 0.4064)
			(end 0.7874 -0.4064)
			(stroke
				(width 0.1524)
				(type default)
			)
			(layer "B.SilkS")
		)
		(fp_line
			(start -0.7874 0.4064)
			(end 0.7874 0.4064)
			(stroke
				(width 0.1524)
				(type default)
			)
			(layer "B.SilkS")
		)
		(fp_line
			(start 0.67945 -0.305054)
			(end 0.12065 -0.305054)
			(stroke
				(width 0.1)
				(type default)
			)
			(layer "B.Fab")
		)
		(fp_line
			(start 0.12065 -0.305054)
			(end 0.12065 -0.2794)
			(stroke
				(width 0.1)
				(type default)
			)
			(layer "B.Fab")
		)
		(fp_line
			(start -0.12065 -0.3048)
			(end -0.67945 -0.3048)
			(stroke
				(width 0.1)
				(type default)
			)
			(layer "B.Fab")
		)
		(fp_line
			(start -0.67945 -0.3048)
			(end -0.67945 0.3048)
			(stroke
				(width 0.1)
				(type default)
			)
			(layer "B.Fab")
		)
		(fp_line
			(start 0.12065 -0.2794)
			(end -0.12065 -0.2794)
			(stroke
				(width 0.1)
				(type default)
			)
			(layer "B.Fab")
		)
		(fp_line
			(start -0.12065 -0.2794)
			(end -0.12065 -0.3048)
			(stroke
				(width 0.1)
				(type default)
			)
			(layer "B.Fab")
		)
		(fp_line
			(start 0.12065 0.2794)
			(end 0.12065 0.3048)
			(stroke
				(width 0.1)
				(type default)
			)
			(layer "B.Fab")
		)
		(fp_line
			(start -0.120396 0.2794)
			(end 0.12065 0.2794)
			(stroke
				(width 0.1)
				(type default)
			)
			(layer "B.Fab")
		)
		(fp_line
			(start 0.67945 0.3048)
			(end 0.67945 -0.305054)
			(stroke
				(width 0.1)
				(type default)
			)
			(layer "B.Fab")
		)
		(fp_line
			(start 0.12065 0.3048)
			(end 0.67945 0.3048)
			(stroke
				(width 0.1)
				(type default)
			)
			(layer "B.Fab")
		)
		(fp_line
			(start -0.120396 0.3048)
			(end -0.120396 0.2794)
			(stroke
				(width 0.1)
				(type default)
			)
			(layer "B.Fab")
		)
		(fp_line
			(start -0.67945 0.3048)
			(end -0.120396 0.3048)
			(stroke
				(width 0.1)
				(type default)
			)
			(layer "B.Fab")
		)
		(pad "1" smd circle
			(at 0.40005 0 270)
			(size 0 0)
			(layers "B.Cu" "B.Mask" "B.Paste")
			(net "SMB_1_BMC_GPU_SDA")
		)
		(pad "2" smd circle
			(at -0.40005 0 270)
			(size 0 0)
			(layers "B.Cu" "B.Mask" "B.Paste")
			(net "SMB_PCIE3_3V3AUX_SDA_R")
		)
	)
	(footprint ""
		(layer "B.Cu")
		(at 437.66994 -362.77042 -90)
		(property "Reference" "PC7002"
			(at 0 0 90)
			(layer "B.SilkS")
			(hide yes)
			(effects
				(font
					(size 1.27 1.27)
				)
				(justify mirror)
			)
		)
		(property "Value" ""
			(at 0 0 90)
			(layer "B.Fab")
			(effects
				(font
					(size 1.27 1.27)
				)
				(justify mirror)
			)
		)
		(duplicate_pad_numbers_are_jumpers no)
		(fp_line
			(start -1.524 0.762)
			(end 1.524 0.762)
			(stroke
				(width 0.1524)
				(type default)
			)
			(layer "B.SilkS")
		)
		(fp_line
			(start 1.524 0.762)
			(end 1.524 -0.762)
			(stroke
				(width 0.1524)
				(type default)
			)
			(layer "B.SilkS")
		)
		(fp_line
			(start -1.524 -0.762)
			(end -1.524 0.762)
			(stroke
				(width 0.1524)
				(type default)
			)
			(layer "B.SilkS")
		)
		(fp_line
			(start 1.524 -0.762)
			(end -1.524 -0.762)
			(stroke
				(width 0.1524)
				(type default)
			)
			(layer "B.SilkS")
		)
		(fp_line
			(start -1.1049 0.724916)
			(end -1.1049 -0.724916)
			(stroke
				(width 0.1)
				(type default)
			)
			(layer "B.Fab")
		)
		(fp_line
			(start 1.1049 0.724916)
			(end -1.1049 0.724916)
			(stroke
				(width 0.1)
				(type default)
			)
			(layer "B.Fab")
		)
		(fp_line
			(start -1.1049 -0.724916)
			(end 1.1049 -0.724916)
			(stroke
				(width 0.1)
				(type default)
			)
			(layer "B.Fab")
		)
		(fp_line
			(start 1.1049 -0.724916)
			(end 1.1049 0.724916)
			(stroke
				(width 0.1)
				(type default)
			)
			(layer "B.Fab")
		)
		(pad "1" smd rect
			(at 0.889 0 270)
			(size 1.016 1.27)
			(layers "B.Cu" "B.Mask" "B.Paste")
			(net "SW_P12V_AUX_PVDD11_S3_P0_FLT")
		)
		(pad "2" smd rect
			(at -0.889 0 270)
			(size 1.016 1.27)
			(layers "B.Cu" "B.Mask" "B.Paste")
			(net "GND")
		)
	)
)
